(kicad_pcb
	(version 20260206)
	(generator "pcbnew")
	(generator_version "10.0")
	(general
		(thickness 1.6)
		(legacy_teardrops no)
	)
	(paper "A4")
	(title_block
		(title "03242023_DA0F0TMBIJ0_F0T_Motherboard_J_brd_V01_OCP.brd")
		(comment 1 "Grand Teton / footprints 2233-2236 of 6105")
	)
	(layers
		(0 "F.Cu" signal "TOP")
		(4 "In1.Cu" signal "GND")
		(6 "In2.Cu" signal "IN1")
		(8 "In3.Cu" signal "GND1")
		(10 "In4.Cu" signal "IN2")
		(12 "In5.Cu" signal "GND2")
		(14 "In6.Cu" signal "IN3")
		(16 "In7.Cu" signal "GND3")
		(18 "In8.Cu" signal "VCC")
		(20 "In9.Cu" signal "VCC1")
		(22 "In10.Cu" signal "GND4")
		(24 "In11.Cu" signal "IN4")
		(26 "In12.Cu" signal "GND5")
		(28 "In13.Cu" signal "IN5")
		(30 "In14.Cu" signal "GND6")
		(32 "In15.Cu" signal "IN6")
		(34 "In16.Cu" signal "GND7")
		(2 "B.Cu" signal "BOTTOM")
		(9 "F.Adhes" user "F.Adhesive")
		(11 "B.Adhes" user "B.Adhesive")
		(13 "F.Paste" user "Package Geometry/Pastemask Top")
		(15 "B.Paste" user "Package Geometry/Pastemask Bottom")
		(5 "F.SilkS" user "Ref Des/Silkscreen Top")
		(7 "B.SilkS" user "Ref Des/Silkscreen Bottom")
		(1 "F.Mask" user "Board Geometry/Soldermask Top")
		(3 "B.Mask" user "Board Geometry/Soldermask Bottom")
		(17 "Dwgs.User" user "User.Drawings")
		(19 "Cmts.User" user "User.Comments")
		(21 "Eco1.User" user "User.Eco1")
		(23 "Eco2.User" user "User.Eco2")
		(25 "Edge.Cuts" user "Board Geometry/Outline")
		(27 "Margin" user)
		(31 "F.CrtYd" user "Package Geometry/Place Bound Top")
		(29 "B.CrtYd" user "Package Geometry/Place Bound Bottom")
		(35 "F.Fab" user "Ref Des/Assembly Top")
		(33 "B.Fab" user "Ref Des/Assembly Bottom")
	)
	(footprint ""
		(layer "F.Cu")
		(at 365.844328 -333.525368 -90)
		(property "Reference" "PC272_P0_4"
			(at 0 0 270)
			(layer "F.SilkS")
			(hide yes)
			(effects
				(font
					(size 1.27 1.27)
				)
			)
		)
		(property "Value" ""
			(at 0 0 270)
			(layer "F.Fab")
			(effects
				(font
					(size 1.27 1.27)
				)
			)
		)
		(duplicate_pad_numbers_are_jumpers no)
		(fp_line
			(start -0.7874 0.4064)
			(end -0.7874 -0.4064)
			(stroke
				(width 0.1524)
				(type default)
			)
			(layer "F.SilkS")
		)
		(fp_line
			(start 0.7874 0.4064)
			(end -0.7874 0.4064)
			(stroke
				(width 0.1524)
				(type default)
			)
			(layer "F.SilkS")
		)
		(fp_line
			(start -0.7874 -0.4064)
			(end 0.7874 -0.4064)
			(stroke
				(width 0.1524)
				(type default)
			)
			(layer "F.SilkS")
		)
		(fp_line
			(start 0.7874 -0.4064)
			(end 0.7874 0.4064)
			(stroke
				(width 0.1524)
				(type default)
			)
			(layer "F.SilkS")
		)
		(fp_line
			(start -0.67945 0.3048)
			(end -0.67945 -0.305054)
			(stroke
				(width 0.1)
				(type default)
			)
			(layer "F.Fab")
		)
		(fp_line
			(start -0.12065 0.3048)
			(end -0.67945 0.3048)
			(stroke
				(width 0.1)
				(type default)
			)
			(layer "F.Fab")
		)
		(fp_line
			(start 0.120396 0.3048)
			(end 0.120396 0.2794)
			(stroke
				(width 0.1)
				(type default)
			)
			(layer "F.Fab")
		)
		(fp_line
			(start 0.67945 0.3048)
			(end 0.120396 0.3048)
			(stroke
				(width 0.1)
				(type default)
			)
			(layer "F.Fab")
		)
		(fp_line
			(start -0.12065 0.2794)
			(end -0.12065 0.3048)
			(stroke
				(width 0.1)
				(type default)
			)
			(layer "F.Fab")
		)
		(fp_line
			(start 0.120396 0.2794)
			(end -0.12065 0.2794)
			(stroke
				(width 0.1)
				(type default)
			)
			(layer "F.Fab")
		)
		(fp_line
			(start -0.12065 -0.2794)
			(end 0.12065 -0.2794)
			(stroke
				(width 0.1)
				(type default)
			)
			(layer "F.Fab")
		)
		(fp_line
			(start 0.12065 -0.2794)
			(end 0.12065 -0.3048)
			(stroke
				(width 0.1)
				(type default)
			)
			(layer "F.Fab")
		)
		(fp_line
			(start 0.12065 -0.3048)
			(end 0.67945 -0.3048)
			(stroke
				(width 0.1)
				(type default)
			)
			(layer "F.Fab")
		)
		(fp_line
			(start 0.67945 -0.3048)
			(end 0.67945 0.3048)
			(stroke
				(width 0.1)
				(type default)
			)
			(layer "F.Fab")
		)
		(fp_line
			(start -0.67945 -0.305054)
			(end -0.12065 -0.305054)
			(stroke
				(width 0.1)
				(type default)
			)
			(layer "F.Fab")
		)
		(fp_line
			(start -0.12065 -0.305054)
			(end -0.12065 -0.2794)
			(stroke
				(width 0.1)
				(type default)
			)
			(layer "F.Fab")
		)
		(pad "1" smd circle
			(at -0.40005 0 270)
			(size 0 0)
			(layers "F.Cu" "F.Mask" "F.Paste")
			(net "PVCCIN_CPU0_PVCC")
		)
		(pad "2" smd circle
			(at 0.40005 0 270)
			(size 0 0)
			(layers "F.Cu" "F.Mask" "F.Paste")
			(net "GND")
		)
	)
	(footprint ""
		(layer "F.Cu")
		(at 128.016 -60.416948)
		(property "Reference" "R4635"
			(at 0 0 0)
			(layer "F.SilkS")
			(hide yes)
			(effects
				(font
					(size 1.27 1.27)
				)
			)
		)
		(property "Value" ""
			(at 0 0 0)
			(layer "F.Fab")
			(effects
				(font
					(size 1.27 1.27)
				)
			)
		)
		(duplicate_pad_numbers_are_jumpers no)
		(fp_line
			(start -0.7874 -0.4064)
			(end 0.7874 -0.4064)
			(stroke
				(width 0.1524)
				(type default)
			)
			(layer "F.SilkS")
		)
		(fp_line
			(start -0.7874 0.4064)
			(end -0.7874 -0.4064)
			(stroke
				(width 0.1524)
				(type default)
			)
			(layer "F.SilkS")
		)
		(fp_line
			(start 0.7874 -0.4064)
			(end 0.7874 0.4064)
			(stroke
				(width 0.1524)
				(type default)
			)
			(layer "F.SilkS")
		)
		(fp_line
			(start 0.7874 0.4064)
			(end -0.7874 0.4064)
			(stroke
				(width 0.1524)
				(type default)
			)
			(layer "F.SilkS")
		)
		(fp_line
			(start -0.67945 -0.305054)
			(end -0.12065 -0.305054)
			(stroke
				(width 0.1)
				(type default)
			)
			(layer "F.Fab")
		)
		(fp_line
			(start -0.67945 0.3048)
			(end -0.67945 -0.305054)
			(stroke
				(width 0.1)
				(type default)
			)
			(layer "F.Fab")
		)
		(fp_line
			(start -0.12065 -0.305054)
			(end -0.12065 -0.2794)
			(stroke
				(width 0.1)
				(type default)
			)
			(layer "F.Fab")
		)
		(fp_line
			(start -0.12065 -0.2794)
			(end 0.12065 -0.2794)
			(stroke
				(width 0.1)
				(type default)
			)
			(layer "F.Fab")
		)
		(fp_line
			(start -0.12065 0.2794)
			(end -0.12065 0.3048)
			(stroke
				(width 0.1)
				(type default)
			)
			(layer "F.Fab")
		)
		(fp_line
			(start -0.12065 0.3048)
			(end -0.67945 0.3048)
			(stroke
				(width 0.1)
				(type default)
			)
			(layer "F.Fab")
		)
		(fp_line
			(start 0.120396 0.2794)
			(end -0.12065 0.2794)
			(stroke
				(width 0.1)
				(type default)
			)
			(layer "F.Fab")
		)
		(fp_line
			(start 0.120396 0.3048)
			(end 0.120396 0.2794)
			(stroke
				(width 0.1)
				(type default)
			)
			(layer "F.Fab")
		)
		(fp_line
			(start 0.12065 -0.3048)
			(end 0.67945 -0.3048)
			(stroke
				(width 0.1)
				(type default)
			)
			(layer "F.Fab")
		)
		(fp_line
			(start 0.12065 -0.2794)
			(end 0.12065 -0.3048)
			(stroke
				(width 0.1)
				(type default)
			)
			(layer "F.Fab")
		)
		(fp_line
			(start 0.67945 -0.3048)
			(end 0.67945 0.3048)
			(stroke
				(width 0.1)
				(type default)
			)
			(layer "F.Fab")
		)
		(fp_line
			(start 0.67945 0.3048)
			(end 0.120396 0.3048)
			(stroke
				(width 0.1)
				(type default)
			)
			(layer "F.Fab")
		)
		(pad "1" smd circle
			(at -0.40005 0)
			(size 0 0)
			(layers "F.Cu" "F.Mask" "F.Paste")
			(net "JTAG_BMC_SW_OE")
		)
		(pad "2" smd circle
			(at 0.40005 0)
			(size 0 0)
			(layers "F.Cu" "F.Mask" "F.Paste")
			(net "GND")
		)
	)
	(footprint ""
		(layer "F.Cu")
		(at 12.786106 -105.50398 90)
		(property "Reference" "R2787"
			(at 0 0 90)
			(layer "F.SilkS")
			(hide yes)
			(effects
				(font
					(size 1.27 1.27)
				)
			)
		)
		(property "Value" ""
			(at 0 0 90)
			(layer "F.Fab")
			(effects
				(font
					(size 1.27 1.27)
				)
			)
		)
		(duplicate_pad_numbers_are_jumpers no)
		(fp_line
			(start 0.7874 -0.4064)
			(end 0.7874 0.4064)
			(stroke
				(width 0.1524)
				(type default)
			)
			(layer "F.SilkS")
		)
		(fp_line
			(start -0.7874 -0.4064)
			(end 0.06604 -0.4064)
			(stroke
				(width 0.1524)
				(type default)
			)
			(layer "F.SilkS")
		)
		(fp_line
			(start 0.7874 0.4064)
			(end -0.7874 0.4064)
			(stroke
				(width 0.1524)
				(type default)
			)
			(layer "F.SilkS")
		)
		(fp_line
			(start -0.12065 -0.305054)
			(end -0.12065 -0.2794)
			(stroke
				(width 0.1)
				(type default)
			)
			(layer "F.Fab")
		)
		(fp_line
			(start -0.67945 -0.305054)
			(end -0.12065 -0.305054)
			(stroke
				(width 0.1)
				(type default)
			)
			(layer "F.Fab")
		)
		(fp_line
			(start 0.67945 -0.3048)
			(end 0.67945 0.3048)
			(stroke
				(width 0.1)
				(type default)
			)
			(layer "F.Fab")
		)
		(fp_line
			(start 0.12065 -0.3048)
			(end 0.67945 -0.3048)
			(stroke
				(width 0.1)
				(type default)
			)
			(layer "F.Fab")
		)
		(fp_line
			(start 0.12065 -0.2794)
			(end 0.12065 -0.3048)
			(stroke
				(width 0.1)
				(type default)
			)
			(layer "F.Fab")
		)
		(fp_line
			(start -0.12065 -0.2794)
			(end 0.12065 -0.2794)
			(stroke
				(width 0.1)
				(type default)
			)
			(layer "F.Fab")
		)
		(fp_line
			(start 0.120396 0.2794)
			(end -0.12065 0.2794)
			(stroke
				(width 0.1)
				(type default)
			)
			(layer "F.Fab")
		)
		(fp_line
			(start -0.12065 0.2794)
			(end -0.12065 0.3048)
			(stroke
				(width 0.1)
				(type default)
			)
			(layer "F.Fab")
		)
		(fp_line
			(start 0.67945 0.3048)
			(end 0.120396 0.3048)
			(stroke
				(width 0.1)
				(type default)
			)
			(layer "F.Fab")
		)
		(fp_line
			(start 0.120396 0.3048)
			(end 0.120396 0.2794)
			(stroke
				(width 0.1)
				(type default)
			)
			(layer "F.Fab")
		)
		(fp_line
			(start -0.12065 0.3048)
			(end -0.67945 0.3048)
			(stroke
				(width 0.1)
				(type default)
			)
			(layer "F.Fab")
		)
		(fp_line
			(start -0.67945 0.3048)
			(end -0.67945 -0.305054)
			(stroke
				(width 0.1)
				(type default)
			)
			(layer "F.Fab")
		)
		(pad "1" smd rect
			(at -0.40005 0 270)
			(size 0.4572 0.508)
			(layers "F.Cu" "F.Mask" "F.Paste")
			(net "USB2_HUB_SWB_DN")
		)
		(pad "2" smd rect
			(at 0.40005 0 270)
			(size 0.4572 0.508)
			(layers "F.Cu" "F.Mask" "F.Paste")
			(net "USB2_HUB_BUF_SWB_R_DN")
		)
	)
	(footprint ""
		(layer "F.Cu")
		(at 121.47931 -333.716122)
		(property "Reference" "PU27_P1_4"
			(at 3.92049 -12.962636 0)
			(unlocked yes)
			(layer "F.SilkS")
			(effects
				(font
					(size 0.7874 0.5842)
					(thickness 0.1524)
				)
				(justify left)
			)
		)
		(property "Value" ""
			(at 0 0 0)
			(layer "F.Fab")
			(effects
				(font
					(size 1.27 1.27)
				)
			)
		)
		(duplicate_pad_numbers_are_jumpers no)
		(fp_line
			(start -2.500122 -2.999994)
			(end -2.24409 -2.999994)
			(stroke
				(width 0.1524)
				(type default)
			)
			(layer "F.SilkS")
		)
		(fp_line
			(start -2.500122 -2.529078)
			(end -2.500122 -2.999994)
			(stroke
				(width 0.1524)
				(type default)
			)
			(layer "F.SilkS")
		)
		(fp_line
			(start -2.500122 0.6604)
			(end -2.500122 0.229108)
			(stroke
				(width 0.1524)
				(type default)
			)
			(layer "F.SilkS")
		)
		(fp_line
			(start -2.500122 2.999994)
			(end -2.500122 2.339594)
			(stroke
				(width 0.1524)
				(type default)
			)
			(layer "F.SilkS")
		)
		(fp_line
			(start -2.2987 2.999994)
			(end -2.500122 2.999994)
			(stroke
				(width 0.1524)
				(type default)
			)
			(layer "F.SilkS")
		)
		(fp_line
			(start 2.31394 -2.999994)
			(end 2.500122 -2.999994)
			(stroke
				(width 0.1524)
				(type default)
			)
			(layer "F.SilkS")
		)
		(fp_line
			(start 2.500122 -2.999994)
			(end 2.500122 -2.44348)
			(stroke
				(width 0.1524)
				(type default)
			)
			(layer "F.SilkS")
		)
		(fp_line
			(start 2.500122 2.339594)
			(end 2.500122 2.999994)
			(stroke
				(width 0.1524)
				(type default)
			)
			(layer "F.SilkS")
		)
		(fp_line
			(start 2.500122 2.999994)
			(end 2.2987 2.999994)
			(stroke
				(width 0.1524)
				(type default)
			)
			(layer "F.SilkS")
		)
		(fp_poly
			(pts
				(xy -2.226818 -3.642868) (xy -2.734818 -2.626868) (xy -3.242818 -3.642868)
			)
			(stroke
				(width 0)
				(type default)
			)
			(fill yes)
			(layer "F.SilkS")
		)
		(fp_line
			(start -2.500122 -2.999994)
			(end 2.500122 -2.999994)
			(stroke
				(width 0.1)
				(type default)
			)
			(layer "F.Fab")
		)
		(fp_line
			(start -2.500122 2.999994)
			(end -2.500122 -2.999994)
			(stroke
				(width 0.1)
				(type default)
			)
			(layer "F.Fab")
		)
		(fp_line
			(start 2.500122 -2.999994)
			(end 2.500122 2.999994)
			(stroke
				(width 0.1)
				(type default)
			)
			(layer "F.Fab")
		)
		(fp_line
			(start 2.500122 2.999994)
			(end -2.500122 2.999994)
			(stroke
				(width 0.1)
				(type default)
			)
			(layer "F.Fab")
		)
		(fp_poly
			(pts
				(xy -4.218432 -2.783078) (xy -4.218432 -1.767078) (xy -3.202432 -2.275078)
			)
			(stroke
				(width 0)
				(type default)
			)
			(fill yes)
			(layer "F.Fab")
		)
		(pad "1" smd rect
			(at -2.400046 -2.275078 90)
			(size 0.2286 0.6096)
			(layers "F.Cu" "F.Mask" "F.Paste")
			(net "PVCCIN_CPU1_VOS4")
		)
		(pad "2" smd rect
			(at -2.400046 -1.82499 90)
			(size 0.2286 0.6096)
			(layers "F.Cu" "F.Mask" "F.Paste")
			(net "GND")
		)
		(pad "3" smd rect
			(at -2.400046 -1.374902 90)
			(size 0.2286 0.6096)
			(layers "F.Cu" "F.Mask" "F.Paste")
			(net "PVCCIN_CPU1_VDD4")
		)
		(pad "4" smd rect
			(at -2.400046 -0.925068 90)
			(size 0.2286 0.6096)
			(layers "F.Cu" "F.Mask" "F.Paste")
			(net "PVCCIN_CPU1_PVCC")
		)
		(pad "5" smd rect
			(at -2.400046 -0.47498 90)
			(size 0.2286 0.6096)
			(layers "F.Cu" "F.Mask" "F.Paste")
			(net "GND")
		)
		(pad "6" smd rect
			(at -2.400046 -0.024892 90)
			(size 0.2286 0.6096)
			(layers "F.Cu" "F.Mask" "F.Paste")
			(net "Net_8529")
		)
		(pad "7_9-20_24" smd circle
			(at 0 1.150112 90)
			(size 0 0)
			(layers "F.Cu" "F.Mask" "F.Paste")
			(net "GND")
		)
		(pad "10_19" smd rect
			(at 0 2.899918 90)
			(size 0.6096 4.318)
			(layers "F.Cu" "F.Mask" "F.Paste")
			(net "SW_PVCCIN_CPU1_SW4")
		)
		(pad "25_29" smd rect
			(at 1.549908 -1.279906 270)
			(size 2.0574 2.3114)
			(layers "F.Cu" "F.Mask" "F.Paste")
			(net "SW_P12V_PVCCIN_CPU1_FLT")
		)
		(pad "30" smd rect
			(at 2.05994 -2.899918)
			(size 0.2286 0.6096)
			(layers "F.Cu" "F.Mask" "F.Paste")
			(net "SW_P12V_PVCCIN_CPU1_FLT")
		)
		(pad "31" smd rect
			(at 1.610106 -2.899918)
			(size 0.2286 0.6096)
			(layers "F.Cu" "F.Mask" "F.Paste")
			(net "Net_8530")
		)
		(pad "32" smd rect
			(at 1.160018 -2.899918)
			(size 0.2286 0.6096)
			(layers "F.Cu" "F.Mask" "F.Paste")
			(net "SW_PVCCIN_CPU1_BOOTR4")
		)
		(pad "33" smd rect
			(at 0.70993 -2.899918)
			(size 0.2286 0.6096)
			(layers "F.Cu" "F.Mask" "F.Paste")
			(net "SW_PVCCIN_CPU1_BOOT4")
		)
		(pad "34" smd rect
			(at 0.260096 -2.899918)
			(size 0.2286 0.6096)
			(layers "F.Cu" "F.Mask" "F.Paste")
			(net "PVCCIN_CPU1_PWM4")
		)
		(pad "35" smd rect
			(at -0.189992 -2.899918)
			(size 0.2286 0.6096)
			(layers "F.Cu" "F.Mask" "F.Paste")
			(net "PVCCIN_CPU1_VDD4")
		)
		(pad "36" smd rect
			(at -0.64008 -2.899918)
			(size 0.2286 0.6096)
			(layers "F.Cu" "F.Mask" "F.Paste")
			(net "PVCCIN_CPU1_ATSEN")
		)
		(pad "37" smd rect
			(at -1.089914 -2.899918)
			(size 0.2286 0.6096)
			(layers "F.Cu" "F.Mask" "F.Paste")
			(net "PVCCIN_CPU1_LSET4")
		)
		(pad "38" smd rect
			(at -1.540002 -2.899918)
			(size 0.2286 0.6096)
			(layers "F.Cu" "F.Mask" "F.Paste")
			(net "PVCCIN_CPU1_IMON4")
		)
		(pad "39" smd rect
			(at -1.99009 -2.899918)
			(size 0.2286 0.6096)
			(layers "F.Cu" "F.Mask" "F.Paste")
			(net "PVCCIN_CPU1_VREF")
		)
		(pad "40" smd rect
			(at -0.87503 -1.27508)
			(size 1.7526 1.9558)
			(layers "F.Cu" "F.Mask" "F.Paste")
			(net "GND")
		)
		(pad "41" smd rect
			(at -1.525016 0.249936 270)
			(size 0.3048 0.4572)
			(layers "F.Cu" "F.Mask" "F.Paste")
			(net "Net_8528")
		)
		(zone
			(layer "F.Cu")
			(hatch none 0.5)
			(connect_pads
				(clearance 0)
			)
			(min_thickness 0.25)
			(keepout
				(tracks not_allowed)
				(vias allowed)
				(pads allowed)
				(copperpour not_allowed)
				(footprints allowed)
			)
			(placement
				(enabled no)
				(sheetname "")
			)
			(fill
				(thermal_gap 0.5)
				(thermal_bridge_width 0.5)
				(island_removal_mode 0)
			)
			(polygon
				(pts
					(xy 118.979188 -330.716128) (xy 118.979188 -331.465428) (xy 123.979432 -331.465428) (xy 123.979432 -330.716128)
					(xy 123.68911 -330.716128) (xy 123.68911 -331.171804) (xy 119.26951 -331.171804) (xy 119.26951 -330.716128)
				)
			)
		)
		(zone
			(layer "F.Cu")
			(hatch none 0.5)
			(connect_pads
				(clearance 0)
			)
			(min_thickness 0.25)
			(keepout
				(tracks not_allowed)
				(vias allowed)
				(pads allowed)
				(copperpour not_allowed)
				(footprints allowed)
			)
			(placement
				(enabled no)
				(sheetname "")
			)
			(fill
				(thermal_gap 0.5)
				(thermal_bridge_width 0.5)
				(island_removal_mode 0)
			)
			(polygon
				(pts
					(xy 119.434864 -334.020668) (xy 119.67718 -334.020668) (xy 119.67718 -333.962502) (xy 120.46458 -333.962502)
					(xy 120.46458 -333.619348) (xy 120.528588 -333.619348) (xy 120.528588 -332.966822) (xy 118.979188 -332.966822)
					(xy 118.979188 -333.423514) (xy 119.674894 -333.423514) (xy 119.674894 -333.262986) (xy 120.233694 -333.262986)
					(xy 120.233694 -333.669386) (xy 119.674894 -333.669386) (xy 119.674894 -333.448914) (xy 118.979188 -333.448914)
					(xy 118.979188 -333.575914) (xy 119.434864 -333.575914)
				)
			)
		)
	)
)
